(kicad_pcb
	(version 20260206)
	(generator "pcbnew")
	(generator_version "10.0")
	(general
		(thickness 1.6)
		(legacy_teardrops no)
	)
	(paper "A4")
	(title_block
		(title "03242023_DA0F0TMBIJ0_F0T_Motherboard_J_brd_V01_OCP.brd")
		(comment 1 "Grand Teton / footprints 5980-5986 of 6105")
	)
	(layers
		(0 "F.Cu" signal "TOP")
		(4 "In1.Cu" signal "GND")
		(6 "In2.Cu" signal "IN1")
		(8 "In3.Cu" signal "GND1")
		(10 "In4.Cu" signal "IN2")
		(12 "In5.Cu" signal "GND2")
		(14 "In6.Cu" signal "IN3")
		(16 "In7.Cu" signal "GND3")
		(18 "In8.Cu" signal "VCC")
		(20 "In9.Cu" signal "VCC1")
		(22 "In10.Cu" signal "GND4")
		(24 "In11.Cu" signal "IN4")
		(26 "In12.Cu" signal "GND5")
		(28 "In13.Cu" signal "IN5")
		(30 "In14.Cu" signal "GND6")
		(32 "In15.Cu" signal "IN6")
		(34 "In16.Cu" signal "GND7")
		(2 "B.Cu" signal "BOTTOM")
		(9 "F.Adhes" user "F.Adhesive")
		(11 "B.Adhes" user "B.Adhesive")
		(13 "F.Paste" user "Package Geometry/Pastemask Top")
		(15 "B.Paste" user "Package Geometry/Pastemask Bottom")
		(5 "F.SilkS" user "Ref Des/Silkscreen Top")
		(7 "B.SilkS" user "Ref Des/Silkscreen Bottom")
		(1 "F.Mask" user "Board Geometry/Soldermask Top")
		(3 "B.Mask" user "Board Geometry/Soldermask Bottom")
		(17 "Dwgs.User" user "User.Drawings")
		(19 "Cmts.User" user "User.Comments")
		(21 "Eco1.User" user "User.Eco1")
		(23 "Eco2.User" user "User.Eco2")
		(25 "Edge.Cuts" user "Board Geometry/Outline")
		(27 "Margin" user)
		(31 "F.CrtYd" user "Package Geometry/Place Bound Top")
		(29 "B.CrtYd" user "Package Geometry/Place Bound Bottom")
		(35 "F.Fab" user "Ref Des/Assembly Top")
		(33 "B.Fab" user "Ref Des/Assembly Bottom")
	)
	(footprint ""
		(layer "B.Cu")
		(at 119.07012 -237.709456 -90)
		(property "Reference" "C488"
			(at 0 0 90)
			(layer "B.SilkS")
			(hide yes)
			(effects
				(font
					(size 1.27 1.27)
				)
				(justify mirror)
			)
		)
		(property "Value" ""
			(at 0 0 90)
			(layer "B.Fab")
			(effects
				(font
					(size 1.27 1.27)
				)
				(justify mirror)
			)
		)
		(duplicate_pad_numbers_are_jumpers no)
		(fp_line
			(start -1.2954 0.5842)
			(end 1.2954 0.5842)
			(stroke
				(width 0.1524)
				(type default)
			)
			(layer "B.SilkS")
		)
		(fp_line
			(start 1.2954 0.5842)
			(end 1.2954 -0.5842)
			(stroke
				(width 0.1524)
				(type default)
			)
			(layer "B.SilkS")
		)
		(fp_line
			(start -1.2954 -0.5842)
			(end -1.2954 0.5842)
			(stroke
				(width 0.1524)
				(type default)
			)
			(layer "B.SilkS")
		)
		(fp_line
			(start 0 -0.5842)
			(end 0 0.5842)
			(stroke
				(width 0.1524)
				(type default)
			)
			(layer "B.SilkS")
		)
		(fp_line
			(start 1.2954 -0.5842)
			(end -1.2954 -0.5842)
			(stroke
				(width 0.1524)
				(type default)
			)
			(layer "B.SilkS")
		)
		(fp_line
			(start -0.8636 0.4572)
			(end 0.8636 0.4572)
			(stroke
				(width 0.1)
				(type default)
			)
			(layer "B.Fab")
		)
		(fp_line
			(start 0.8636 0.4572)
			(end 0.8636 0.4064)
			(stroke
				(width 0.1)
				(type default)
			)
			(layer "B.Fab")
		)
		(fp_line
			(start -1.1938 0.4064)
			(end -0.8636 0.4064)
			(stroke
				(width 0.1)
				(type default)
			)
			(layer "B.Fab")
		)
		(fp_line
			(start -0.8636 0.4064)
			(end -0.8636 0.4572)
			(stroke
				(width 0.1)
				(type default)
			)
			(layer "B.Fab")
		)
		(fp_line
			(start 0.8636 0.4064)
			(end 1.1938 0.4064)
			(stroke
				(width 0.1)
				(type default)
			)
			(layer "B.Fab")
		)
		(fp_line
			(start 1.1938 0.4064)
			(end 1.1938 -0.4064)
			(stroke
				(width 0.1)
				(type default)
			)
			(layer "B.Fab")
		)
		(fp_line
			(start -1.1938 -0.4064)
			(end -1.1938 0.4064)
			(stroke
				(width 0.1)
				(type default)
			)
			(layer "B.Fab")
		)
		(fp_line
			(start -0.8636 -0.4064)
			(end -1.1938 -0.4064)
			(stroke
				(width 0.1)
				(type default)
			)
			(layer "B.Fab")
		)
		(fp_line
			(start 0.8636 -0.4064)
			(end 0.8636 -0.4572)
			(stroke
				(width 0.1)
				(type default)
			)
			(layer "B.Fab")
		)
		(fp_line
			(start 1.1938 -0.4064)
			(end 0.8636 -0.4064)
			(stroke
				(width 0.1)
				(type default)
			)
			(layer "B.Fab")
		)
		(fp_line
			(start -0.8636 -0.4572)
			(end -0.8636 -0.4064)
			(stroke
				(width 0.1)
				(type default)
			)
			(layer "B.Fab")
		)
		(fp_line
			(start 0.8636 -0.4572)
			(end -0.8636 -0.4572)
			(stroke
				(width 0.1)
				(type default)
			)
			(layer "B.Fab")
		)
		(pad "1" smd rect
			(at 0.7366 0 180)
			(size 0.7112 0.8128)
			(layers "B.Cu" "B.Mask" "B.Paste")
			(net "PVCCINFAON_CPU1")
		)
		(pad "2" smd rect
			(at -0.7366 0 180)
			(size 0.7112 0.8128)
			(layers "B.Cu" "B.Mask" "B.Paste")
			(net "GND")
		)
	)
	(footprint ""
		(layer "B.Cu")
		(at 303.09312 -353.878134 -90)
		(property "Reference" "PC618_P0_2"
			(at 0 0 90)
			(layer "B.SilkS")
			(hide yes)
			(effects
				(font
					(size 1.27 1.27)
				)
				(justify mirror)
			)
		)
		(property "Value" ""
			(at 0 0 90)
			(layer "B.Fab")
			(effects
				(font
					(size 1.27 1.27)
				)
				(justify mirror)
			)
		)
		(duplicate_pad_numbers_are_jumpers no)
		(fp_line
			(start -1.524 0.762)
			(end 1.524 0.762)
			(stroke
				(width 0.1524)
				(type default)
			)
			(layer "B.SilkS")
		)
		(fp_line
			(start 1.524 0.762)
			(end 1.524 -0.762)
			(stroke
				(width 0.1524)
				(type default)
			)
			(layer "B.SilkS")
		)
		(fp_line
			(start -1.524 -0.762)
			(end -1.524 0.762)
			(stroke
				(width 0.1524)
				(type default)
			)
			(layer "B.SilkS")
		)
		(fp_line
			(start 1.524 -0.762)
			(end -1.524 -0.762)
			(stroke
				(width 0.1524)
				(type default)
			)
			(layer "B.SilkS")
		)
		(fp_line
			(start -1.1049 0.724916)
			(end -1.1049 -0.724916)
			(stroke
				(width 0.1)
				(type default)
			)
			(layer "B.Fab")
		)
		(fp_line
			(start 1.1049 0.724916)
			(end -1.1049 0.724916)
			(stroke
				(width 0.1)
				(type default)
			)
			(layer "B.Fab")
		)
		(fp_line
			(start -1.1049 -0.724916)
			(end 1.1049 -0.724916)
			(stroke
				(width 0.1)
				(type default)
			)
			(layer "B.Fab")
		)
		(fp_line
			(start 1.1049 -0.724916)
			(end 1.1049 0.724916)
			(stroke
				(width 0.1)
				(type default)
			)
			(layer "B.Fab")
		)
		(pad "1" smd rect
			(at 0.889 0 270)
			(size 1.016 1.27)
			(layers "B.Cu" "B.Mask" "B.Paste")
			(net "PVCCFA_EHV_FIVRA_CPU0")
		)
		(pad "2" smd rect
			(at -0.889 0 270)
			(size 1.016 1.27)
			(layers "B.Cu" "B.Mask" "B.Paste")
			(net "GND")
		)
	)
	(footprint ""
		(layer "B.Cu")
		(at 423.079164 -366.466374 -90)
		(property "Reference" "PR1324"
			(at 0 0 90)
			(layer "B.SilkS")
			(hide yes)
			(effects
				(font
					(size 1.27 1.27)
				)
				(justify mirror)
			)
		)
		(property "Value" ""
			(at 0 0 90)
			(layer "B.Fab")
			(effects
				(font
					(size 1.27 1.27)
				)
				(justify mirror)
			)
		)
		(duplicate_pad_numbers_are_jumpers no)
		(fp_line
			(start -0.7874 0.4064)
			(end 0.7874 0.4064)
			(stroke
				(width 0.1524)
				(type default)
			)
			(layer "B.SilkS")
		)
		(fp_line
			(start 0.7874 0.4064)
			(end 0.7874 -0.4064)
			(stroke
				(width 0.1524)
				(type default)
			)
			(layer "B.SilkS")
		)
		(fp_line
			(start -0.7874 -0.4064)
			(end -0.7874 0.4064)
			(stroke
				(width 0.1524)
				(type default)
			)
			(layer "B.SilkS")
		)
		(fp_line
			(start 0.7874 -0.4064)
			(end -0.7874 -0.4064)
			(stroke
				(width 0.1524)
				(type default)
			)
			(layer "B.SilkS")
		)
		(fp_line
			(start -0.67945 0.3048)
			(end -0.120396 0.3048)
			(stroke
				(width 0.1)
				(type default)
			)
			(layer "B.Fab")
		)
		(fp_line
			(start -0.120396 0.3048)
			(end -0.120396 0.2794)
			(stroke
				(width 0.1)
				(type default)
			)
			(layer "B.Fab")
		)
		(fp_line
			(start 0.12065 0.3048)
			(end 0.67945 0.3048)
			(stroke
				(width 0.1)
				(type default)
			)
			(layer "B.Fab")
		)
		(fp_line
			(start 0.67945 0.3048)
			(end 0.67945 -0.305054)
			(stroke
				(width 0.1)
				(type default)
			)
			(layer "B.Fab")
		)
		(fp_line
			(start -0.120396 0.2794)
			(end 0.12065 0.2794)
			(stroke
				(width 0.1)
				(type default)
			)
			(layer "B.Fab")
		)
		(fp_line
			(start 0.12065 0.2794)
			(end 0.12065 0.3048)
			(stroke
				(width 0.1)
				(type default)
			)
			(layer "B.Fab")
		)
		(fp_line
			(start -0.12065 -0.2794)
			(end -0.12065 -0.3048)
			(stroke
				(width 0.1)
				(type default)
			)
			(layer "B.Fab")
		)
		(fp_line
			(start 0.12065 -0.2794)
			(end -0.12065 -0.2794)
			(stroke
				(width 0.1)
				(type default)
			)
			(layer "B.Fab")
		)
		(fp_line
			(start -0.67945 -0.3048)
			(end -0.67945 0.3048)
			(stroke
				(width 0.1)
				(type default)
			)
			(layer "B.Fab")
		)
		(fp_line
			(start -0.12065 -0.3048)
			(end -0.67945 -0.3048)
			(stroke
				(width 0.1)
				(type default)
			)
			(layer "B.Fab")
		)
		(fp_line
			(start 0.12065 -0.305054)
			(end 0.12065 -0.2794)
			(stroke
				(width 0.1)
				(type default)
			)
			(layer "B.Fab")
		)
		(fp_line
			(start 0.67945 -0.305054)
			(end 0.12065 -0.305054)
			(stroke
				(width 0.1)
				(type default)
			)
			(layer "B.Fab")
		)
		(pad "1" smd circle
			(at 0.40005 0 90)
			(size 0 0)
			(layers "B.Cu" "B.Mask" "B.Paste")
			(net "PVCCFA_EHV_FIVRA_CPU0_VOS3")
		)
		(pad "2" smd circle
			(at -0.40005 0 90)
			(size 0 0)
			(layers "B.Cu" "B.Mask" "B.Paste")
			(net "PVCCFA_EHV_FIVRA_CPU0")
		)
	)
	(footprint ""
		(layer "B.Cu")
		(at 112.020604 -294.01008)
		(property "Reference" "C341"
			(at 0 0 0)
			(layer "B.SilkS")
			(hide yes)
			(effects
				(font
					(size 1.27 1.27)
				)
				(justify mirror)
			)
		)
		(property "Value" ""
			(at 0 0 0)
			(layer "B.Fab")
			(effects
				(font
					(size 1.27 1.27)
				)
				(justify mirror)
			)
		)
		(duplicate_pad_numbers_are_jumpers no)
		(fp_line
			(start -1.524 -0.762)
			(end -1.524 0.762)
			(stroke
				(width 0.1524)
				(type default)
			)
			(layer "B.SilkS")
		)
		(fp_line
			(start -1.524 0.762)
			(end 1.524 0.762)
			(stroke
				(width 0.1524)
				(type default)
			)
			(layer "B.SilkS")
		)
		(fp_line
			(start 1.524 -0.762)
			(end -1.524 -0.762)
			(stroke
				(width 0.1524)
				(type default)
			)
			(layer "B.SilkS")
		)
		(fp_line
			(start 1.524 0.762)
			(end 1.524 -0.762)
			(stroke
				(width 0.1524)
				(type default)
			)
			(layer "B.SilkS")
		)
		(fp_line
			(start -1.1049 -0.724916)
			(end 1.1049 -0.724916)
			(stroke
				(width 0.1)
				(type default)
			)
			(layer "B.Fab")
		)
		(fp_line
			(start -1.1049 0.724916)
			(end -1.1049 -0.724916)
			(stroke
				(width 0.1)
				(type default)
			)
			(layer "B.Fab")
		)
		(fp_line
			(start 1.1049 -0.724916)
			(end 1.1049 0.724916)
			(stroke
				(width 0.1)
				(type default)
			)
			(layer "B.Fab")
		)
		(fp_line
			(start 1.1049 0.724916)
			(end -1.1049 0.724916)
			(stroke
				(width 0.1)
				(type default)
			)
			(layer "B.Fab")
		)
		(pad "1" smd rect
			(at 0.889 0)
			(size 1.016 1.27)
			(layers "B.Cu" "B.Mask" "B.Paste")
			(net "PVCCIN_CPU1")
		)
		(pad "2" smd rect
			(at -0.889 0)
			(size 1.016 1.27)
			(layers "B.Cu" "B.Mask" "B.Paste")
			(net "GND")
		)
	)
	(footprint ""
		(layer "B.Cu")
		(at 189.28588 -130.266948 -90)
		(property "Reference" "R1741"
			(at 0 0 90)
			(layer "B.SilkS")
			(hide yes)
			(effects
				(font
					(size 1.27 1.27)
				)
				(justify mirror)
			)
		)
		(property "Value" ""
			(at 0 0 90)
			(layer "B.Fab")
			(effects
				(font
					(size 1.27 1.27)
				)
				(justify mirror)
			)
		)
		(duplicate_pad_numbers_are_jumpers no)
		(fp_line
			(start -0.7874 0.4064)
			(end 0.7874 0.4064)
			(stroke
				(width 0.1524)
				(type default)
			)
			(layer "B.SilkS")
		)
		(fp_line
			(start 0.7874 0.4064)
			(end 0.7874 -0.4064)
			(stroke
				(width 0.1524)
				(type default)
			)
			(layer "B.SilkS")
		)
		(fp_line
			(start -0.7874 -0.4064)
			(end -0.7874 0.4064)
			(stroke
				(width 0.1524)
				(type default)
			)
			(layer "B.SilkS")
		)
		(fp_line
			(start 0.7874 -0.4064)
			(end -0.7874 -0.4064)
			(stroke
				(width 0.1524)
				(type default)
			)
			(layer "B.SilkS")
		)
		(fp_line
			(start -0.67945 0.3048)
			(end -0.120396 0.3048)
			(stroke
				(width 0.1)
				(type default)
			)
			(layer "B.Fab")
		)
		(fp_line
			(start -0.120396 0.3048)
			(end -0.120396 0.2794)
			(stroke
				(width 0.1)
				(type default)
			)
			(layer "B.Fab")
		)
		(fp_line
			(start 0.12065 0.3048)
			(end 0.67945 0.3048)
			(stroke
				(width 0.1)
				(type default)
			)
			(layer "B.Fab")
		)
		(fp_line
			(start 0.67945 0.3048)
			(end 0.67945 -0.305054)
			(stroke
				(width 0.1)
				(type default)
			)
			(layer "B.Fab")
		)
		(fp_line
			(start -0.120396 0.2794)
			(end 0.12065 0.2794)
			(stroke
				(width 0.1)
				(type default)
			)
			(layer "B.Fab")
		)
		(fp_line
			(start 0.12065 0.2794)
			(end 0.12065 0.3048)
			(stroke
				(width 0.1)
				(type default)
			)
			(layer "B.Fab")
		)
		(fp_line
			(start -0.12065 -0.2794)
			(end -0.12065 -0.3048)
			(stroke
				(width 0.1)
				(type default)
			)
			(layer "B.Fab")
		)
		(fp_line
			(start 0.12065 -0.2794)
			(end -0.12065 -0.2794)
			(stroke
				(width 0.1)
				(type default)
			)
			(layer "B.Fab")
		)
		(fp_line
			(start -0.67945 -0.3048)
			(end -0.67945 0.3048)
			(stroke
				(width 0.1)
				(type default)
			)
			(layer "B.Fab")
		)
		(fp_line
			(start -0.12065 -0.3048)
			(end -0.67945 -0.3048)
			(stroke
				(width 0.1)
				(type default)
			)
			(layer "B.Fab")
		)
		(fp_line
			(start 0.12065 -0.305054)
			(end 0.12065 -0.2794)
			(stroke
				(width 0.1)
				(type default)
			)
			(layer "B.Fab")
		)
		(fp_line
			(start 0.67945 -0.305054)
			(end 0.12065 -0.305054)
			(stroke
				(width 0.1)
				(type default)
			)
			(layer "B.Fab")
		)
		(pad "1" smd circle
			(at 0.40005 0 90)
			(size 0 0)
			(layers "B.Cu" "B.Mask" "B.Paste")
			(net "FM_RST_PERST_BIT0")
		)
		(pad "2" smd circle
			(at -0.40005 0 90)
			(size 0 0)
			(layers "B.Cu" "B.Mask" "B.Paste")
			(net "P3V3_AUX")
		)
	)
	(footprint ""
		(layer "B.Cu")
		(at 103.901494 -244.82044 -90)
		(property "Reference" "C313"
			(at 0 0 90)
			(layer "B.SilkS")
			(hide yes)
			(effects
				(font
					(size 1.27 1.27)
				)
				(justify mirror)
			)
		)
		(property "Value" ""
			(at 0 0 90)
			(layer "B.Fab")
			(effects
				(font
					(size 1.27 1.27)
				)
				(justify mirror)
			)
		)
		(duplicate_pad_numbers_are_jumpers no)
		(fp_line
			(start -1.524 0.762)
			(end 1.524 0.762)
			(stroke
				(width 0.1524)
				(type default)
			)
			(layer "B.SilkS")
		)
		(fp_line
			(start 1.524 0.762)
			(end 1.524 -0.762)
			(stroke
				(width 0.1524)
				(type default)
			)
			(layer "B.SilkS")
		)
		(fp_line
			(start -1.524 -0.762)
			(end -1.524 0.762)
			(stroke
				(width 0.1524)
				(type default)
			)
			(layer "B.SilkS")
		)
		(fp_line
			(start 1.524 -0.762)
			(end -1.524 -0.762)
			(stroke
				(width 0.1524)
				(type default)
			)
			(layer "B.SilkS")
		)
		(fp_line
			(start -1.1049 0.724916)
			(end -1.1049 -0.724916)
			(stroke
				(width 0.1)
				(type default)
			)
			(layer "B.Fab")
		)
		(fp_line
			(start 1.1049 0.724916)
			(end -1.1049 0.724916)
			(stroke
				(width 0.1)
				(type default)
			)
			(layer "B.Fab")
		)
		(fp_line
			(start -1.1049 -0.724916)
			(end 1.1049 -0.724916)
			(stroke
				(width 0.1)
				(type default)
			)
			(layer "B.Fab")
		)
		(fp_line
			(start 1.1049 -0.724916)
			(end 1.1049 0.724916)
			(stroke
				(width 0.1)
				(type default)
			)
			(layer "B.Fab")
		)
		(pad "1" smd rect
			(at 0.889 0 270)
			(size 1.016 1.27)
			(layers "B.Cu" "B.Mask" "B.Paste")
			(net "PVCCIN_CPU1")
		)
		(pad "2" smd rect
			(at -0.889 0 270)
			(size 1.016 1.27)
			(layers "B.Cu" "B.Mask" "B.Paste")
			(net "GND")
		)
	)
	(footprint ""
		(layer "B.Cu")
		(at 434.089302 -318.868806 90)
		(property "Reference" "R942"
			(at 0 0 90)
			(layer "B.SilkS")
			(hide yes)
			(effects
				(font
					(size 1.27 1.27)
				)
				(justify mirror)
			)
		)
		(property "Value" ""
			(at 0 0 90)
			(layer "B.Fab")
			(effects
				(font
					(size 1.27 1.27)
				)
				(justify mirror)
			)
		)
		(duplicate_pad_numbers_are_jumpers no)
		(fp_line
			(start 0.7874 -0.4064)
			(end -0.7874 -0.4064)
			(stroke
				(width 0.1524)
				(type default)
			)
			(layer "B.SilkS")
		)
		(fp_line
			(start -0.7874 -0.4064)
			(end -0.7874 0.4064)
			(stroke
				(width 0.1524)
				(type default)
			)
			(layer "B.SilkS")
		)
		(fp_line
			(start 0.7874 0.4064)
			(end 0.7874 -0.4064)
			(stroke
				(width 0.1524)
				(type default)
			)
			(layer "B.SilkS")
		)
		(fp_line
			(start -0.7874 0.4064)
			(end 0.7874 0.4064)
			(stroke
				(width 0.1524)
				(type default)
			)
			(layer "B.SilkS")
		)
		(fp_line
			(start 0.67945 -0.305054)
			(end 0.12065 -0.305054)
			(stroke
				(width 0.1)
				(type default)
			)
			(layer "B.Fab")
		)
		(fp_line
			(start 0.12065 -0.305054)
			(end 0.12065 -0.2794)
			(stroke
				(width 0.1)
				(type default)
			)
			(layer "B.Fab")
		)
		(fp_line
			(start -0.12065 -0.3048)
			(end -0.67945 -0.3048)
			(stroke
				(width 0.1)
				(type default)
			)
			(layer "B.Fab")
		)
		(fp_line
			(start -0.67945 -0.3048)
			(end -0.67945 0.3048)
			(stroke
				(width 0.1)
				(type default)
			)
			(layer "B.Fab")
		)
		(fp_line
			(start 0.12065 -0.2794)
			(end -0.12065 -0.2794)
			(stroke
				(width 0.1)
				(type default)
			)
			(layer "B.Fab")
		)
		(fp_line
			(start -0.12065 -0.2794)
			(end -0.12065 -0.3048)
			(stroke
				(width 0.1)
				(type default)
			)
			(layer "B.Fab")
		)
		(fp_line
			(start 0.12065 0.2794)
			(end 0.12065 0.3048)
			(stroke
				(width 0.1)
				(type default)
			)
			(layer "B.Fab")
		)
		(fp_line
			(start -0.120396 0.2794)
			(end 0.12065 0.2794)
			(stroke
				(width 0.1)
				(type default)
			)
			(layer "B.Fab")
		)
		(fp_line
			(start 0.67945 0.3048)
			(end 0.67945 -0.305054)
			(stroke
				(width 0.1)
				(type default)
			)
			(layer "B.Fab")
		)
		(fp_line
			(start 0.12065 0.3048)
			(end 0.67945 0.3048)
			(stroke
				(width 0.1)
				(type default)
			)
			(layer "B.Fab")
		)
		(fp_line
			(start -0.120396 0.3048)
			(end -0.120396 0.2794)
			(stroke
				(width 0.1)
				(type default)
			)
			(layer "B.Fab")
		)
		(fp_line
			(start -0.67945 0.3048)
			(end -0.120396 0.3048)
			(stroke
				(width 0.1)
				(type default)
			)
			(layer "B.Fab")
		)
		(pad "1" smd circle
			(at 0.40005 0 270)
			(size 0 0)
			(layers "B.Cu" "B.Mask" "B.Paste")
			(net "P3V3_AUX")
		)
		(pad "2" smd circle
			(at -0.40005 0 270)
			(size 0 0)
			(layers "B.Cu" "B.Mask" "B.Paste")
			(net "PWRGD_FAIL_CPU0_EF_R1")
		)
	)
)
